FILE_TYPE = MACRO_DRAWING;
SET COLOR_WIRE YELLOW;
SET COLOR_PROP ORANGE;
SET COLOR_DOT WHITE;
SET COLOR_ARC YELLOW;
SET COLOR_BODY GREEN;
SET COLOR_NOTE PURPLE;
SET PROP_DISPLAY VALUE;
SET PAGE_NUMBER P121;
FORCEADD OFFPAGE..1
(-3000 -1475);
FORCEPROP 2 LAST $XR0 216 
J 0
(-3252 -1475);
DISPLAY 0.638298 (-3252 -1475);
PAINT MONO (-3252 -1475);
FORCEPROP 1 LAST COMMENT_BODY TRUE
J 0
(-2875 -1575);
DISPLAY 0.872340 (-2875 -1575);
PAINT GREEN (-2875 -1575);
DISPLAY INVISIBLE (-2875 -1575);
FORCEPROP 1 LAST OFFPAGE TRUE
J 0
(-2675 -1600);
DISPLAY 0.872340 (-2675 -1600);
PAINT GREEN (-2675 -1600);
DISPLAY INVISIBLE (-2675 -1600);
FORCEPROP 2 LAST CDS_LIB standard
J 0
(-3000 -1475);
PAINT MONO (-3000 -1475);
DISPLAY INVISIBLE (-3000 -1475);
FORCEPROP 2 LAST PATH I1
J 0
(-3250 -1425);
DISPLAY 1.021277 (-3250 -1425);
DISPLAY INVISIBLE (-3250 -1425);
FORCEADD Q_RES..1
(100 600);
FORCEPROP 1 LAST PART_NUMBER CS21502FB07
J 0
(50 700);
DISPLAY 0.787234 (50 700);
DISPLAY INVISIBLE (50 700);
FORCEPROP 1 LAST VALUE 1.5K
J 2
(75 500);
DISPLAY 0.638298 (75 500);
FORCEPROP 1 LAST MATERIAL CHIP
J 0
(100 450);
DISPLAY 0.638298 (100 450);
FORCEPROP 1 LAST PACK_TYPE 0402LF
J 0
(200 500);
DISPLAY 0.638298 (200 500);
FORCEPROP 1 LAST $LOCATION R4398
J 0
(-100 600);
DISPLAY 0.638298 (-100 600);
FORCEPROP 1 LASTPIN (0 600) $PN 1
J 0
(12 612);
DISPLAY 0.787234 (12 612);
PAINT MONO (12 612);
FORCEPROP 1 LASTPIN (200 600) $PN 2
J 0
(162 612);
DISPLAY 0.787234 (162 612);
PAINT MONO (162 612);
FORCEPROP 1 LAST WATTAGE 1/16W
J 2
(75 450);
DISPLAY 0.638298 (75 450);
DISPLAY INVISIBLE (75 450);
FORCEPROP 1 LAST TOLERANCE 1%
J 0
(100 500);
DISPLAY 0.638298 (100 500);
DISPLAY INVISIBLE (100 500);
FORCEPROP 2 LAST CDS_LIB pure_quanta
J 0
(100 600);
DISPLAY INVISIBLE (100 600);
FORCEPROP 1 LAST PATH I10
J 0
(50 750);
DISPLAY 0.978723 (50 750);
PAINT WHITE (50 750);
DISPLAY INVISIBLE (50 750);
FORCEPROP 0 LAST CDS_LOCATION R4398
J 0
(-75 650);
DISPLAY 1.021277 (-75 650);
DISPLAY INVISIBLE (-75 650);
FORCEPROP 0 LAST $SEC 1
J 0
(-75 650);
DISPLAY 0.680851 (-75 650);
PAINT MONO (-75 650);
DISPLAY INVISIBLE (-75 650);
FORCEPROP 0 LAST CDS_SEC 1
J 0
(-75 650);
DISPLAY 1.021277 (-75 650);
DISPLAY INVISIBLE (-75 650);
FORCEADD OFFPAGE..1
(-3100 2200);
FORCEPROP 2 LAST $XR0 14 
J 0
(-3321 2200);
DISPLAY 0.638298 (-3321 2200);
PAINT MONO (-3321 2200);
FORCEPROP 1 LAST COMMENT_BODY TRUE
J 0
(-2975 2100);
DISPLAY 0.872340 (-2975 2100);
PAINT GREEN (-2975 2100);
DISPLAY INVISIBLE (-2975 2100);
FORCEPROP 1 LAST OFFPAGE TRUE
J 0
(-2775 2075);
DISPLAY 0.872340 (-2775 2075);
PAINT GREEN (-2775 2075);
DISPLAY INVISIBLE (-2775 2075);
FORCEPROP 2 LAST CDS_LIB standard
J 0
(-3100 2200);
PAINT MONO (-3100 2200);
DISPLAY INVISIBLE (-3100 2200);
FORCEPROP 2 LAST PATH I11
J 0
(-3300 2250);
DISPLAY 1.021277 (-3300 2250);
DISPLAY INVISIBLE (-3300 2250);
FORCEADD UNIVERSAL_POWER..1
(-2025 1325);
FORCEPROP 3 LASTPIN (-2025 1275) SIG_NAME PVNN_TERM_CPU1\g
J 0
(-2015 1285);
DISPLAY 0.659574 (-2015 1285);
PAINT MONO (-2015 1285);
DISPLAY INVISIBLE (-2015 1285);
FORCEPROP 1 LAST HDL_POWER PVNN_TERM_CPU1
J 1
(-2025 1375);
DISPLAY 0.872340 (-2025 1375);
PAINT GREEN (-2025 1375);
FORCEPROP 2 LAST CDS_LIB logical_power
J 0
(-2025 1325);
DISPLAY INVISIBLE (-2025 1325);
FORCEPROP 1 LAST PATH I12
J 0
(-1975 1350);
DISPLAY 0.872340 (-1975 1350);
PAINT AQUA (-1975 1350);
DISPLAY INVISIBLE (-1975 1350);
FORCEADD Q_RES..2
(-2025 2475);
FORCEPROP 1 LAST PART_NUMBER CS11002FB07
J 0
(-2000 2300);
DISPLAY 0.510638 (-2000 2300);
DISPLAY INVISIBLE (-2000 2300);
FORCEPROP 1 LAST WATTAGE 1/16W
J 0
(-2000 2400);
DISPLAY 0.510638 (-2000 2400);
FORCEPROP 1 LAST VALUE 100
J 0
(-1995 2500);
DISPLAY 0.510638 (-1995 2500);
FORCEPROP 1 LAST TOLERANCE 1%
J 0
(-1995 2450);
DISPLAY 0.510638 (-1995 2450);
FORCEPROP 1 LAST MATERIAL CHIP
J 0
(-2000 2350);
DISPLAY 0.510638 (-2000 2350);
FORCEPROP 1 LAST PACK_TYPE 0402LF
J 0
(-2000 2250);
DISPLAY 0.510638 (-2000 2250);
FORCEPROP 1 LAST $LOCATION R4395
J 0
(-1995 2550);
DISPLAY 0.638298 (-1995 2550);
FORCEPROP 1 LASTPIN (-2025 2575) $PN 1
J 0
(-2020 2537);
DISPLAY 0.787234 (-2020 2537);
PAINT MONO (-2020 2537);
FORCEPROP 1 LASTPIN (-2025 2375) $PN 2
J 0
(-2020 2385);
DISPLAY 0.787234 (-2020 2385);
PAINT MONO (-2020 2385);
FORCEPROP 2 LAST CDS_LIB pure_quanta
J 0
(-2025 2475);
DISPLAY INVISIBLE (-2025 2475);
FORCEPROP 1 LAST PATH I13
J 0
(-1975 2650);
DISPLAY 0.978723 (-1975 2650);
PAINT WHITE (-1975 2650);
DISPLAY INVISIBLE (-1975 2650);
FORCEPROP 0 LAST CDS_LOCATION R4395
J 0
(-1975 2600);
DISPLAY 1.021277 (-1975 2600);
DISPLAY INVISIBLE (-1975 2600);
FORCEPROP 0 LAST $SEC 1
J 0
(-1975 2600);
DISPLAY 0.680851 (-1975 2600);
PAINT MONO (-1975 2600);
DISPLAY INVISIBLE (-1975 2600);
FORCEPROP 0 LAST CDS_SEC 1
J 0
(-1975 2600);
DISPLAY 1.021277 (-1975 2600);
DISPLAY INVISIBLE (-1975 2600);
FORCEADD UNIVERSAL_POWER..1
(-2025 2675);
FORCEPROP 3 LASTPIN (-2025 2625) SIG_NAME PVNN_TERM_CPU0\g
J 0
(-2015 2635);
DISPLAY 0.659574 (-2015 2635);
PAINT MONO (-2015 2635);
DISPLAY INVISIBLE (-2015 2635);
FORCEPROP 1 LAST HDL_POWER PVNN_TERM_CPU0
J 1
(-2025 2725);
DISPLAY 0.872340 (-2025 2725);
PAINT GREEN (-2025 2725);
FORCEPROP 2 LAST CDS_LIB logical_power
J 0
(-2025 2675);
DISPLAY INVISIBLE (-2025 2675);
FORCEPROP 1 LAST PATH I14
J 0
(-1975 2700);
DISPLAY 0.872340 (-1975 2700);
PAINT AQUA (-1975 2700);
DISPLAY INVISIBLE (-1975 2700);
FORCEADD Q_RES..1
(-1650 2200);
FORCEPROP 1 LAST PART_NUMBER CS21502FB07
J 0
(-1700 2300);
DISPLAY 0.787234 (-1700 2300);
DISPLAY INVISIBLE (-1700 2300);
FORCEPROP 1 LAST VALUE 1.5K
J 2
(-1675 2100);
DISPLAY 0.638298 (-1675 2100);
FORCEPROP 1 LAST WATTAGE 1/16W
J 2
(-1675 2050);
DISPLAY 0.638298 (-1675 2050);
FORCEPROP 1 LAST TOLERANCE 1%
J 0
(-1650 2100);
DISPLAY 0.638298 (-1650 2100);
FORCEPROP 1 LAST MATERIAL CHIP
J 0
(-1650 2050);
DISPLAY 0.638298 (-1650 2050);
FORCEPROP 1 LAST PACK_TYPE 0402LF
J 0
(-1550 2100);
DISPLAY 0.638298 (-1550 2100);
FORCEPROP 1 LAST LOCATION R237
J 0
(-1850 2200);
DISPLAY 0.638298 (-1850 2200);
FORCEPROP 1 LASTPIN (-1750 2200) $PN 1
J 0
(-1738 2212);
DISPLAY 0.787234 (-1738 2212);
PAINT MONO (-1738 2212);
FORCEPROP 1 LASTPIN (-1550 2200) $PN 2
J 0
(-1588 2212);
DISPLAY 0.787234 (-1588 2212);
PAINT MONO (-1588 2212);
FORCEPROP 2 LAST CDS_LIB pure_quanta
J 0
(-1650 2200);
DISPLAY INVISIBLE (-1650 2200);
FORCEPROP 1 LAST PATH I15
J 0
(-1700 2350);
DISPLAY 0.978723 (-1700 2350);
PAINT WHITE (-1700 2350);
DISPLAY INVISIBLE (-1700 2350);
FORCEPROP 0 LAST $SEC 1
J 0
(-1700 2350);
DISPLAY 0.680851 (-1700 2350);
PAINT MONO (-1700 2350);
DISPLAY INVISIBLE (-1700 2350);
FORCEPROP 0 LAST CDS_SEC 1
J 0
(-1700 2350);
DISPLAY 1.021277 (-1700 2350);
DISPLAY INVISIBLE (-1700 2350);
FORCEADD Q_RES..1
(100 1950);
FORCEPROP 1 LAST PART_NUMBER CS21502FB07
J 0
(50 2050);
DISPLAY 0.787234 (50 2050);
DISPLAY INVISIBLE (50 2050);
FORCEPROP 1 LAST MATERIAL CHIP
J 0
(100 1800);
DISPLAY 0.638298 (100 1800);
FORCEPROP 1 LAST PACK_TYPE 0402LF
J 0
(200 1850);
DISPLAY 0.638298 (200 1850);
FORCEPROP 1 LAST VALUE 1.5K
J 2
(75 1850);
DISPLAY 0.638298 (75 1850);
FORCEPROP 1 LAST $LOCATION R4397
J 0
(-100 1950);
DISPLAY 0.638298 (-100 1950);
FORCEPROP 1 LASTPIN (0 1950) $PN 1
J 0
(12 1962);
DISPLAY 0.787234 (12 1962);
PAINT MONO (12 1962);
FORCEPROP 1 LASTPIN (200 1950) $PN 2
J 0
(162 1962);
DISPLAY 0.787234 (162 1962);
PAINT MONO (162 1962);
FORCEPROP 1 LAST WATTAGE 1/16W
J 2
(75 1800);
DISPLAY 0.638298 (75 1800);
DISPLAY INVISIBLE (75 1800);
FORCEPROP 1 LAST TOLERANCE 1%
J 0
(100 1850);
DISPLAY 0.638298 (100 1850);
DISPLAY INVISIBLE (100 1850);
FORCEPROP 2 LAST CDS_LIB pure_quanta
J 0
(100 1950);
DISPLAY INVISIBLE (100 1950);
FORCEPROP 1 LAST PATH I16
J 0
(50 2100);
DISPLAY 0.978723 (50 2100);
PAINT WHITE (50 2100);
DISPLAY INVISIBLE (50 2100);
FORCEPROP 0 LAST CDS_LOCATION R4397
J 0
(-75 2000);
DISPLAY 1.021277 (-75 2000);
DISPLAY INVISIBLE (-75 2000);
FORCEPROP 0 LAST $SEC 1
J 0
(-75 2000);
DISPLAY 0.680851 (-75 2000);
PAINT MONO (-75 2000);
DISPLAY INVISIBLE (-75 2000);
FORCEPROP 0 LAST CDS_SEC 1
J 0
(-75 2000);
DISPLAY 1.021277 (-75 2000);
DISPLAY INVISIBLE (-75 2000);
FORCEADD BC847BPN..2
(-675 2200);
FORCEPROP 1 LAST PART_NUMBER BA008470026
J 0
(-620 2044);
DISPLAY 0.723404 (-620 2044);
PAINT GREEN (-620 2044);
DISPLAY INVISIBLE (-620 2044);
FORCEPROP 2 LAST VALUE BC847BPN
J 0
(-600 2200);
DISPLAY 1.021277 (-600 2200);
FORCEPROP 1 LAST MATERIAL IC
J 0
(-620 1957);
DISPLAY 0.723404 (-620 1957);
PAINT GREEN (-620 1957);
FORCEPROP 2 LAST PART_TYPE SMLF
J 0
(-600 2250);
DISPLAY 1.021277 (-600 2250);
FORCEPROP 1 LAST LOCATION Q138
J 0
(-620 2151);
DISPLAY 0.723404 (-620 2151);
PAINT GREEN (-620 2151);
FORCEPROP 0 LASTPIN (-775 2200) $PN 5
J 2
(-785 2210);
DISPLAY 0.680851 (-785 2210);
PAINT MONO (-785 2210);
FORCEPROP 0 LASTPIN (-625 2100) $PN 3
R 1
J 2
(-635 2090);
DISPLAY 0.680851 (-635 2090);
PAINT MONO (-635 2090);
FORCEPROP 0 LASTPIN (-625 2300) $PN 4
R 1
J 0
(-635 2310);
DISPLAY 0.680851 (-635 2310);
PAINT MONO (-635 2310);
FORCEPROP 1 LAST CDS_LMAN_SYM_OUTLINE -50,50,50,-50
J 0
(-675 2200);
DISPLAY 0.468085 (-675 2200);
PAINT GREEN (-675 2200);
DISPLAY INVISIBLE (-675 2200);
FORCEPROP 1 LAST NEEDS_NO_SIZE TRUE
J 0
(-675 2200);
DISPLAY 0.723404 (-675 2200);
PAINT GREEN (-675 2200);
DISPLAY INVISIBLE (-675 2200);
FORCEPROP 2 LAST CDS_LIB pure_quanta
J 0
(-675 2200);
DISPLAY INVISIBLE (-675 2200);
FORCEPROP 1 LAST PATH I17
J 0
(-675 2200);
DISPLAY 0.723404 (-675 2200);
PAINT GREEN (-675 2200);
DISPLAY INVISIBLE (-675 2200);
FORCEPROP 0 LAST $SEC 2
J 0
(-600 2300);
DISPLAY 0.680851 (-600 2300);
PAINT MONO (-600 2300);
DISPLAY INVISIBLE (-600 2300);
FORCEPROP 0 LAST CDS_SEC 2
J 0
(-600 2300);
DISPLAY 1.021277 (-600 2300);
DISPLAY INVISIBLE (-600 2300);
FORCEADD UNIVERSAL_POWER..1
(-625 2450);
FORCEPROP 3 LASTPIN (-625 2400) SIG_NAME PVNN_TERM_CPU0\g
J 0
(-615 2410);
DISPLAY 0.659574 (-615 2410);
PAINT MONO (-615 2410);
DISPLAY INVISIBLE (-615 2410);
FORCEPROP 1 LAST HDL_POWER PVNN_TERM_CPU0
J 1
(-625 2500);
DISPLAY 0.872340 (-625 2500);
PAINT GREEN (-625 2500);
FORCEPROP 2 LAST CDS_LIB logical_power
J 0
(-625 2450);
DISPLAY INVISIBLE (-625 2450);
FORCEPROP 1 LAST PATH I18
J 0
(-575 2475);
DISPLAY 0.872340 (-575 2475);
PAINT AQUA (-575 2475);
DISPLAY INVISIBLE (-575 2475);
FORCEADD Q_RES..2
(1450 -1225);
FORCEPROP 1 LAST PART_NUMBER CS11002FB07
J 0
(1490 -1350);
DISPLAY 0.638298 (1490 -1350);
DISPLAY INVISIBLE (1490 -1350);
FORCEPROP 1 LAST PACK_TYPE 0402LF
J 0
(1490 -1400);
DISPLAY 0.638298 (1490 -1400);
FORCEPROP 1 LAST VALUE 100
J 0
(1495 -1150);
DISPLAY 0.638298 (1495 -1150);
FORCEPROP 1 LAST TOLERANCE 1%
J 0
(1495 -1200);
DISPLAY 0.638298 (1495 -1200);
FORCEPROP 1 LAST WATTAGE 1/16W
J 0
(1490 -1250);
DISPLAY 0.638298 (1490 -1250);
FORCEPROP 1 LAST MATERIAL CHIP
J 0
(1490 -1300);
DISPLAY 0.638298 (1490 -1300);
FORCEPROP 1 LAST $LOCATION R244
J 0
(1495 -1100);
DISPLAY 0.978723 (1495 -1100);
FORCEPROP 1 LASTPIN (1450 -1125) $PN 1
J 0
(1455 -1163);
DISPLAY 0.787234 (1455 -1163);
FORCEPROP 1 LASTPIN (1450 -1325) $PN 2
J 0
(1455 -1315);
DISPLAY 0.787234 (1455 -1315);
FORCEPROP 2 LAST CDS_LIB pure_quanta
J 0
(1450 -1225);
PAINT MONO (1450 -1225);
DISPLAY INVISIBLE (1450 -1225);
FORCEPROP 1 LAST PATH I19
J 0
(1500 -1050);
DISPLAY 0.978723 (1500 -1050);
PAINT WHITE (1500 -1050);
DISPLAY INVISIBLE (1500 -1050);
FORCEPROP 2 LAST CDS_LOCATION R244
J 0
(1500 -1000);
DISPLAY 1.021277 (1500 -1000);
DISPLAY INVISIBLE (1500 -1000);
FORCEPROP 2 LAST $SEC 1
J 0
(1500 -1000);
DISPLAY 0.680851 (1500 -1000);
PAINT MONO (1500 -1000);
DISPLAY INVISIBLE (1500 -1000);
FORCEPROP 2 LAST CDS_SEC 1
J 0
(1500 -1000);
DISPLAY 1.021277 (1500 -1000);
DISPLAY INVISIBLE (1500 -1000);
FORCEADD OFFPAGE..1
(-3000 -575);
FORCEPROP 2 LAST $XR0 216 
J 0
(-3252 -575);
DISPLAY 0.638298 (-3252 -575);
PAINT MONO (-3252 -575);
FORCEPROP 1 LAST COMMENT_BODY TRUE
J 0
(-2875 -675);
DISPLAY 0.872340 (-2875 -675);
PAINT GREEN (-2875 -675);
DISPLAY INVISIBLE (-2875 -675);
FORCEPROP 1 LAST OFFPAGE TRUE
J 0
(-2675 -700);
DISPLAY 0.872340 (-2675 -700);
PAINT GREEN (-2675 -700);
DISPLAY INVISIBLE (-2675 -700);
FORCEPROP 2 LAST CDS_LIB standard
J 0
(-3000 -575);
PAINT MONO (-3000 -575);
DISPLAY INVISIBLE (-3000 -575);
FORCEPROP 2 LAST PATH I2
J 0
(-3250 -525);
DISPLAY 1.021277 (-3250 -525);
DISPLAY INVISIBLE (-3250 -525);
FORCEADD UNIVERSAL_POWER..1
(1450 -975);
FORCEPROP 3 LASTPIN (1450 -1025) SIG_NAME PVNN_TERM_CPU1\g
J 0
(1460 -1015);
DISPLAY 0.659574 (1460 -1015);
PAINT MONO (1460 -1015);
DISPLAY INVISIBLE (1460 -1015);
FORCEPROP 1 LAST HDL_POWER PVNN_TERM_CPU1
J 1
(1450 -925);
DISPLAY 0.872340 (1450 -925);
PAINT GREEN (1450 -925);
FORCEPROP 2 LAST CDS_LIB logical_power
J 0
(1450 -975);
DISPLAY INVISIBLE (1450 -975);
FORCEPROP 1 LAST PATH I20
J 0
(1500 -950);
DISPLAY 0.872340 (1500 -950);
PAINT AQUA (1500 -950);
DISPLAY INVISIBLE (1500 -950);
FORCEADD BC847BPN..1
(875 600);
FORCEPROP 1 LAST PART_NUMBER BA008470026
J 0
(930 444);
DISPLAY 0.723404 (930 444);
PAINT GREEN (930 444);
DISPLAY INVISIBLE (930 444);
FORCEPROP 2 LAST VALUE BC847BPN
J 0
(950 600);
DISPLAY 1.021277 (950 600);
FORCEPROP 2 LAST PART_TYPE SMLF
J 0
(950 650);
DISPLAY 1.021277 (950 650);
FORCEPROP 1 LAST MATERIAL IC
J 0
(930 357);
DISPLAY 0.723404 (930 357);
PAINT GREEN (930 357);
FORCEPROP 1 LAST LOCATION Q139
J 0
(930 551);
DISPLAY 0.723404 (930 551);
PAINT GREEN (930 551);
FORCEPROP 0 LASTPIN (775 600) $PN 2
J 2
(765 610);
DISPLAY 0.680851 (765 610);
PAINT MONO (765 610);
FORCEPROP 0 LASTPIN (925 500) $PN 6
R 1
J 2
(915 490);
DISPLAY 0.680851 (915 490);
PAINT MONO (915 490);
FORCEPROP 0 LASTPIN (925 700) $PN 1
R 1
J 0
(915 710);
DISPLAY 0.680851 (915 710);
PAINT MONO (915 710);
FORCEPROP 1 LAST CDS_LMAN_SYM_OUTLINE -50,50,50,-50
J 0
(875 600);
DISPLAY 0.468085 (875 600);
PAINT GREEN (875 600);
DISPLAY INVISIBLE (875 600);
FORCEPROP 1 LAST NEEDS_NO_SIZE TRUE
J 0
(875 600);
DISPLAY 0.723404 (875 600);
PAINT GREEN (875 600);
DISPLAY INVISIBLE (875 600);
FORCEPROP 2 LAST CDS_LIB pure_quanta
J 0
(875 600);
DISPLAY INVISIBLE (875 600);
FORCEPROP 1 LAST PATH I21
J 0
(875 600);
DISPLAY 0.723404 (875 600);
PAINT GREEN (875 600);
DISPLAY INVISIBLE (875 600);
FORCEPROP 0 LAST $SEC 1
J 0
(950 700);
DISPLAY 0.680851 (950 700);
PAINT MONO (950 700);
DISPLAY INVISIBLE (950 700);
FORCEPROP 0 LAST CDS_SEC 1
J 0
(950 700);
DISPLAY 1.021277 (950 700);
DISPLAY INVISIBLE (950 700);
FORCEADD UNIVERSAL_GND..1
(975 925);
FORCEPROP 3 LASTPIN (975 975) SIG_NAME GND\g
J 0
(985 985);
DISPLAY 0.659574 (985 985);
PAINT MONO (985 985);
DISPLAY INVISIBLE (985 985);
FORCEPROP 1 LAST HDL_POWER GND
J 1
(1000 850);
DISPLAY 0.872340 (1000 850);
PAINT GREEN (1000 850);
DISPLAY INVISIBLE (1000 850);
FORCEPROP 2 LAST CDS_LIB logical_power
J 0
(975 925);
DISPLAY INVISIBLE (975 925);
FORCEPROP 1 LAST PATH I22
J 0
(1050 925);
DISPLAY 0.872340 (1050 925);
PAINT AQUA (1050 925);
DISPLAY INVISIBLE (1050 925);
FORCEADD Q_RES..2
(1450 -325);
FORCEPROP 1 LAST PART_NUMBER CS11002FB07
J 0
(1490 -450);
DISPLAY 0.638298 (1490 -450);
DISPLAY INVISIBLE (1490 -450);
FORCEPROP 1 LAST PACK_TYPE 0402LF
J 0
(1490 -500);
DISPLAY 0.638298 (1490 -500);
FORCEPROP 1 LAST TOLERANCE 1%
J 0
(1495 -300);
DISPLAY 0.638298 (1495 -300);
FORCEPROP 1 LAST VALUE 100
J 0
(1495 -250);
DISPLAY 0.638298 (1495 -250);
FORCEPROP 1 LAST WATTAGE 1/16W
J 0
(1490 -350);
DISPLAY 0.638298 (1490 -350);
FORCEPROP 1 LAST MATERIAL CHIP
J 0
(1490 -400);
DISPLAY 0.638298 (1490 -400);
FORCEPROP 1 LAST $LOCATION R243
J 0
(1495 -200);
DISPLAY 0.978723 (1495 -200);
FORCEPROP 1 LASTPIN (1450 -225) $PN 1
J 0
(1455 -263);
DISPLAY 0.787234 (1455 -263);
FORCEPROP 1 LASTPIN (1450 -425) $PN 2
J 0
(1455 -415);
DISPLAY 0.787234 (1455 -415);
FORCEPROP 2 LAST CDS_LIB pure_quanta
J 0
(1450 -325);
PAINT MONO (1450 -325);
DISPLAY INVISIBLE (1450 -325);
FORCEPROP 1 LAST PATH I23
J 0
(1500 -150);
DISPLAY 0.978723 (1500 -150);
PAINT WHITE (1500 -150);
DISPLAY INVISIBLE (1500 -150);
FORCEPROP 2 LAST CDS_LOCATION R243
J 0
(1500 -100);
DISPLAY 1.021277 (1500 -100);
DISPLAY INVISIBLE (1500 -100);
FORCEPROP 2 LAST $SEC 1
J 0
(1500 -100);
DISPLAY 0.680851 (1500 -100);
PAINT MONO (1500 -100);
DISPLAY INVISIBLE (1500 -100);
FORCEPROP 2 LAST CDS_SEC 1
J 0
(1500 -100);
DISPLAY 1.021277 (1500 -100);
DISPLAY INVISIBLE (1500 -100);
FORCEADD UNIVERSAL_POWER..1
(1450 -75);
FORCEPROP 3 LASTPIN (1450 -125) SIG_NAME PVNN_TERM_CPU0\g
J 0
(1460 -115);
DISPLAY 0.659574 (1460 -115);
PAINT MONO (1460 -115);
DISPLAY INVISIBLE (1460 -115);
FORCEPROP 1 LAST HDL_POWER PVNN_TERM_CPU0
J 1
(1450 -25);
DISPLAY 0.872340 (1450 -25);
PAINT GREEN (1450 -25);
FORCEPROP 2 LAST CDS_LIB logical_power
J 0
(1450 -75);
DISPLAY INVISIBLE (1450 -75);
FORCEPROP 1 LAST PATH I24
J 0
(1500 -50);
DISPLAY 0.872340 (1500 -50);
PAINT AQUA (1500 -50);
DISPLAY INVISIBLE (1500 -50);
FORCEADD UNIVERSAL_POWER..1
(1725 1000);
FORCEPROP 3 LASTPIN (1725 950) SIG_NAME P3V3\g
J 0
(1735 960);
DISPLAY 0.659574 (1735 960);
PAINT MONO (1735 960);
DISPLAY INVISIBLE (1735 960);
FORCEPROP 1 LAST HDL_POWER P3V3
J 1
(1725 1050);
DISPLAY 0.872340 (1725 1050);
PAINT GREEN (1725 1050);
FORCEPROP 2 LAST CDS_LIB logical_power
J 0
(1725 1000);
PAINT MONO (1725 1000);
DISPLAY INVISIBLE (1725 1000);
FORCEPROP 1 LAST PATH I25
J 0
(1775 1025);
DISPLAY 0.872340 (1775 1025);
PAINT AQUA (1775 1025);
DISPLAY INVISIBLE (1775 1025);
FORCEADD Q_RES..2
(1725 750);
FORCEPROP 1 LAST PART_NUMBER CS24752FB03
J 0
(1750 625);
DISPLAY 0.978723 (1750 625);
DISPLAY INVISIBLE (1750 625);
FORCEPROP 1 LAST WATTAGE 1/16W
J 0
(1765 725);
DISPLAY 0.978723 (1765 725);
FORCEPROP 1 LAST MATERIAL CHIP
J 0
(1765 675);
DISPLAY 0.978723 (1765 675);
FORCEPROP 1 LAST TOLERANCE 1%
J 0
(1770 775);
DISPLAY 0.978723 (1770 775);
FORCEPROP 1 LAST VALUE 4.75K
J 0
(1770 825);
DISPLAY 0.978723 (1770 825);
FORCEPROP 1 LAST PACK_TYPE 0402LF
J 0
(1765 575);
DISPLAY 0.978723 (1765 575);
FORCEPROP 1 LAST LOCATION R242
J 0
(1770 875);
DISPLAY 0.978723 (1770 875);
FORCEPROP 1 LASTPIN (1725 850) $PN 1
J 0
(1730 812);
DISPLAY 0.787234 (1730 812);
PAINT MONO (1730 812);
FORCEPROP 1 LASTPIN (1725 650) $PN 2
J 0
(1730 660);
DISPLAY 0.787234 (1730 660);
PAINT MONO (1730 660);
FORCEPROP 2 LAST CDS_LIB pure_quanta
J 0
(1725 750);
DISPLAY INVISIBLE (1725 750);
FORCEPROP 1 LAST PATH I26
J 0
(1775 925);
DISPLAY 0.978723 (1775 925);
PAINT WHITE (1775 925);
DISPLAY INVISIBLE (1775 925);
FORCEPROP 0 LAST $SEC 1
J 0
(1775 925);
DISPLAY 0.680851 (1775 925);
PAINT MONO (1775 925);
DISPLAY INVISIBLE (1775 925);
FORCEPROP 2 LAST CDS_SEC 1
J 0
(1775 975);
DISPLAY 1.021277 (1775 975);
DISPLAY INVISIBLE (1775 975);
FORCEADD OFFPAGE..2
(2325 -1475);
FORCEPROP 2 LAST $XR0 45 
J 0
(2514 -1475);
DISPLAY 0.638298 (2514 -1475);
PAINT MONO (2514 -1475);
FORCEPROP 1 LAST COMMENT_BODY TRUE
J 0
(2280 -1570);
DISPLAY 0.872340 (2280 -1570);
PAINT GREEN (2280 -1570);
DISPLAY INVISIBLE (2280 -1570);
FORCEPROP 1 LAST OFFPAGE TRUE
J 0
(2650 -1600);
DISPLAY 0.872340 (2650 -1600);
PAINT GREEN (2650 -1600);
DISPLAY INVISIBLE (2650 -1600);
FORCEPROP 2 LAST CDS_LIB standard
J 0
(2325 -1475);
DISPLAY INVISIBLE (2325 -1475);
FORCEPROP 2 LAST PATH I27
J 0
(2525 -1425);
DISPLAY 1.021277 (2525 -1425);
DISPLAY INVISIBLE (2525 -1425);
FORCEADD OFFPAGE..2
(2325 -575);
FORCEPROP 2 LAST $XR0 14 
J 0
(2514 -575);
DISPLAY 0.638298 (2514 -575);
PAINT MONO (2514 -575);
FORCEPROP 1 LAST COMMENT_BODY TRUE
J 0
(2280 -670);
DISPLAY 0.872340 (2280 -670);
PAINT GREEN (2280 -670);
DISPLAY INVISIBLE (2280 -670);
FORCEPROP 1 LAST OFFPAGE TRUE
J 0
(2650 -700);
DISPLAY 0.872340 (2650 -700);
PAINT GREEN (2650 -700);
DISPLAY INVISIBLE (2650 -700);
FORCEPROP 2 LAST CDS_LIB standard
J 0
(2325 -575);
DISPLAY INVISIBLE (2325 -575);
FORCEPROP 2 LAST PATH I28
J 0
(2525 -525);
DISPLAY 1.021277 (2525 -525);
DISPLAY INVISIBLE (2525 -525);
FORCEADD Q_RES..1
(2375 375);
FORCEPROP 1 LAST PART_NUMBER CS03322FB03
J 0
(2325 475);
DISPLAY 0.787234 (2325 475);
DISPLAY INVISIBLE (2325 475);
FORCEPROP 1 LAST VALUE 33.2
J 2
(2350 275);
DISPLAY 0.787234 (2350 275);
FORCEPROP 1 LAST PACK_TYPE 0402LF
J 0
(2625 225);
DISPLAY 0.787234 (2625 225);
FORCEPROP 1 LAST MATERIAL CHIP
J 0
(2375 225);
DISPLAY 0.787234 (2375 225);
FORCEPROP 1 LAST TOLERANCE 1%
J 0
(2375 275);
DISPLAY 0.787234 (2375 275);
FORCEPROP 1 LAST WATTAGE 1/16W
J 2
(2350 225);
DISPLAY 0.787234 (2350 225);
FORCEPROP 1 LAST $LOCATION R4400
J 0
(2150 375);
DISPLAY 0.787234 (2150 375);
FORCEPROP 1 LASTPIN (2275 375) $PN 1
J 0
(2287 387);
DISPLAY 0.787234 (2287 387);
PAINT MONO (2287 387);
FORCEPROP 1 LASTPIN (2475 375) $PN 2
J 0
(2437 387);
DISPLAY 0.787234 (2437 387);
PAINT MONO (2437 387);
FORCEPROP 2 LAST CDS_LIB pure_quanta
J 0
(2375 375);
DISPLAY INVISIBLE (2375 375);
FORCEPROP 1 LAST PATH I29
J 0
(2325 525);
DISPLAY 0.978723 (2325 525);
PAINT WHITE (2325 525);
DISPLAY INVISIBLE (2325 525);
FORCEPROP 0 LAST CDS_LOCATION R4400
J 0
(2325 525);
DISPLAY 1.021277 (2325 525);
DISPLAY INVISIBLE (2325 525);
FORCEPROP 0 LAST $SEC 1
J 0
(2325 525);
DISPLAY 0.680851 (2325 525);
PAINT MONO (2325 525);
DISPLAY INVISIBLE (2325 525);
FORCEPROP 0 LAST CDS_SEC 1
J 0
(2325 525);
DISPLAY 1.021277 (2325 525);
DISPLAY INVISIBLE (2325 525);
FORCEADD OFFPAGE..1
(-3100 850);
FORCEPROP 2 LAST $XR0 45 
J 0
(-3321 850);
DISPLAY 0.638298 (-3321 850);
PAINT MONO (-3321 850);
FORCEPROP 1 LAST COMMENT_BODY TRUE
J 0
(-2975 750);
DISPLAY 0.872340 (-2975 750);
PAINT GREEN (-2975 750);
DISPLAY INVISIBLE (-2975 750);
FORCEPROP 1 LAST OFFPAGE TRUE
J 0
(-2775 725);
DISPLAY 0.872340 (-2775 725);
PAINT GREEN (-2775 725);
DISPLAY INVISIBLE (-2775 725);
FORCEPROP 2 LAST CDS_LIB standard
J 0
(-3100 850);
PAINT MONO (-3100 850);
DISPLAY INVISIBLE (-3100 850);
FORCEPROP 2 LAST PATH I3
J 0
(-3300 900);
DISPLAY 1.021277 (-3300 900);
DISPLAY INVISIBLE (-3300 900);
FORCEADD OFFPAGE..2
(3200 375);
FORCEPROP 2 LAST $XR0 216 
J 0
(3389 375);
DISPLAY 0.638298 (3389 375);
PAINT MONO (3389 375);
FORCEPROP 1 LAST COMMENT_BODY TRUE
J 0
(3155 280);
DISPLAY 0.872340 (3155 280);
PAINT GREEN (3155 280);
DISPLAY INVISIBLE (3155 280);
FORCEPROP 1 LAST OFFPAGE TRUE
J 0
(3525 250);
DISPLAY 0.872340 (3525 250);
PAINT GREEN (3525 250);
DISPLAY INVISIBLE (3525 250);
FORCEPROP 2 LAST CDS_LIB standard
J 0
(3200 375);
DISPLAY INVISIBLE (3200 375);
FORCEPROP 2 LAST PATH I30
J 0
(3400 425);
DISPLAY 1.021277 (3400 425);
DISPLAY INVISIBLE (3400 425);
FORCEADD BC847BPN..1
(875 1950);
FORCEPROP 1 LAST PART_NUMBER BA008470026
J 0
(930 1794);
DISPLAY 0.723404 (930 1794);
PAINT GREEN (930 1794);
DISPLAY INVISIBLE (930 1794);
FORCEPROP 2 LAST VALUE BC847BPN
J 0
(950 1950);
DISPLAY 1.021277 (950 1950);
FORCEPROP 1 LAST MATERIAL IC
J 0
(930 1707);
DISPLAY 0.723404 (930 1707);
PAINT GREEN (930 1707);
FORCEPROP 2 LAST PART_TYPE SMLF
J 0
(950 2000);
DISPLAY 1.021277 (950 2000);
FORCEPROP 1 LAST LOCATION Q138
J 0
(930 1901);
DISPLAY 0.723404 (930 1901);
PAINT GREEN (930 1901);
FORCEPROP 0 LASTPIN (775 1950) $PN 2
J 2
(765 1960);
DISPLAY 0.680851 (765 1960);
PAINT MONO (765 1960);
FORCEPROP 0 LASTPIN (925 1850) $PN 6
R 1
J 2
(915 1840);
DISPLAY 0.680851 (915 1840);
PAINT MONO (915 1840);
FORCEPROP 0 LASTPIN (925 2050) $PN 1
R 1
J 0
(915 2060);
DISPLAY 0.680851 (915 2060);
PAINT MONO (915 2060);
FORCEPROP 1 LAST CDS_LMAN_SYM_OUTLINE -50,50,50,-50
J 0
(875 1950);
DISPLAY 0.468085 (875 1950);
PAINT GREEN (875 1950);
DISPLAY INVISIBLE (875 1950);
FORCEPROP 1 LAST NEEDS_NO_SIZE TRUE
J 0
(875 1950);
DISPLAY 0.723404 (875 1950);
PAINT GREEN (875 1950);
DISPLAY INVISIBLE (875 1950);
FORCEPROP 2 LAST CDS_LIB pure_quanta
J 0
(875 1950);
DISPLAY INVISIBLE (875 1950);
FORCEPROP 1 LAST PATH I31
J 0
(875 1950);
DISPLAY 0.723404 (875 1950);
PAINT GREEN (875 1950);
DISPLAY INVISIBLE (875 1950);
FORCEPROP 0 LAST $SEC 1
J 0
(950 2050);
DISPLAY 0.680851 (950 2050);
PAINT MONO (950 2050);
DISPLAY INVISIBLE (950 2050);
FORCEPROP 0 LAST CDS_SEC 1
J 0
(950 2050);
DISPLAY 1.021277 (950 2050);
DISPLAY INVISIBLE (950 2050);
FORCEADD UNIVERSAL_GND..1
(975 2275);
FORCEPROP 3 LASTPIN (975 2325) SIG_NAME GND\g
J 0
(985 2335);
DISPLAY 0.659574 (985 2335);
PAINT MONO (985 2335);
DISPLAY INVISIBLE (985 2335);
FORCEPROP 1 LAST HDL_POWER GND
J 1
(1000 2200);
DISPLAY 0.872340 (1000 2200);
PAINT GREEN (1000 2200);
DISPLAY INVISIBLE (1000 2200);
FORCEPROP 2 LAST CDS_LIB logical_power
J 0
(975 2275);
DISPLAY INVISIBLE (975 2275);
FORCEPROP 1 LAST PATH I32
J 0
(1050 2275);
DISPLAY 0.872340 (1050 2275);
PAINT AQUA (1050 2275);
DISPLAY INVISIBLE (1050 2275);
FORCEADD Q_RES..2
(1725 2100);
FORCEPROP 1 LAST PART_NUMBER CS24752FB03
J 0
(1750 1975);
DISPLAY 0.978723 (1750 1975);
DISPLAY INVISIBLE (1750 1975);
FORCEPROP 1 LAST WATTAGE 1/16W
J 0
(1765 2075);
DISPLAY 0.978723 (1765 2075);
FORCEPROP 1 LAST MATERIAL CHIP
J 0
(1765 2025);
DISPLAY 0.978723 (1765 2025);
FORCEPROP 1 LAST TOLERANCE 1%
J 0
(1770 2125);
DISPLAY 0.978723 (1770 2125);
FORCEPROP 1 LAST VALUE 4.75K
J 0
(1770 2175);
DISPLAY 0.978723 (1770 2175);
FORCEPROP 1 LAST PACK_TYPE 0402LF
J 0
(1765 1925);
DISPLAY 0.978723 (1765 1925);
FORCEPROP 1 LAST $LOCATION R241
J 0
(1770 2225);
DISPLAY 0.787234 (1770 2225);
FORCEPROP 1 LASTPIN (1725 2200) $PN 1
J 0
(1730 2162);
DISPLAY 0.787234 (1730 2162);
PAINT MONO (1730 2162);
FORCEPROP 1 LASTPIN (1725 2000) $PN 2
J 0
(1730 2010);
DISPLAY 0.787234 (1730 2010);
PAINT MONO (1730 2010);
FORCEPROP 2 LAST CDS_LIB pure_quanta
J 0
(1725 2100);
DISPLAY INVISIBLE (1725 2100);
FORCEPROP 1 LAST PATH I33
J 0
(1775 2275);
DISPLAY 0.978723 (1775 2275);
PAINT WHITE (1775 2275);
DISPLAY INVISIBLE (1775 2275);
FORCEPROP 2 LAST CDS_LOCATION R241
J 0
(1775 2325);
DISPLAY 1.021277 (1775 2325);
DISPLAY INVISIBLE (1775 2325);
FORCEPROP 0 LAST $SEC 1
J 0
(1775 2275);
DISPLAY 0.680851 (1775 2275);
PAINT MONO (1775 2275);
DISPLAY INVISIBLE (1775 2275);
FORCEPROP 2 LAST CDS_SEC 1
J 0
(1775 2325);
DISPLAY 1.021277 (1775 2325);
DISPLAY INVISIBLE (1775 2325);
FORCEADD UNIVERSAL_POWER..1
(1725 2350);
FORCEPROP 3 LASTPIN (1725 2300) SIG_NAME P3V3\g
J 0
(1735 2310);
DISPLAY 0.659574 (1735 2310);
PAINT MONO (1735 2310);
DISPLAY INVISIBLE (1735 2310);
FORCEPROP 1 LAST HDL_POWER P3V3
J 1
(1725 2400);
DISPLAY 0.872340 (1725 2400);
PAINT GREEN (1725 2400);
FORCEPROP 2 LAST CDS_LIB logical_power
J 0
(1725 2350);
PAINT MONO (1725 2350);
DISPLAY INVISIBLE (1725 2350);
FORCEPROP 1 LAST PATH I34
J 0
(1775 2375);
DISPLAY 0.872340 (1775 2375);
PAINT AQUA (1775 2375);
DISPLAY INVISIBLE (1775 2375);
FORCEADD Q_RES..1
(2375 1725);
FORCEPROP 1 LAST PART_NUMBER CS03322FB03
J 0
(2325 1825);
DISPLAY 0.787234 (2325 1825);
DISPLAY INVISIBLE (2325 1825);
FORCEPROP 1 LAST VALUE 33.2
J 2
(2350 1625);
DISPLAY 0.787234 (2350 1625);
FORCEPROP 1 LAST TOLERANCE 1%
J 0
(2375 1625);
DISPLAY 0.787234 (2375 1625);
FORCEPROP 1 LAST WATTAGE 1/16W
J 2
(2350 1575);
DISPLAY 0.787234 (2350 1575);
FORCEPROP 1 LAST PACK_TYPE 0402LF
J 0
(2625 1575);
DISPLAY 0.787234 (2625 1575);
FORCEPROP 1 LAST MATERIAL CHIP
J 0
(2375 1575);
DISPLAY 0.787234 (2375 1575);
FORCEPROP 1 LAST $LOCATION R4399
J 0
(2150 1725);
DISPLAY 0.638298 (2150 1725);
FORCEPROP 1 LASTPIN (2275 1725) $PN 1
J 0
(2287 1737);
DISPLAY 0.787234 (2287 1737);
PAINT MONO (2287 1737);
FORCEPROP 1 LASTPIN (2475 1725) $PN 2
J 0
(2437 1737);
DISPLAY 0.787234 (2437 1737);
PAINT MONO (2437 1737);
FORCEPROP 2 LAST CDS_LIB pure_quanta
J 0
(2375 1725);
DISPLAY INVISIBLE (2375 1725);
FORCEPROP 1 LAST PATH I35
J 0
(2325 1875);
DISPLAY 0.978723 (2325 1875);
PAINT WHITE (2325 1875);
DISPLAY INVISIBLE (2325 1875);
FORCEPROP 0 LAST CDS_LOCATION R4399
J 0
(2325 1875);
DISPLAY 1.021277 (2325 1875);
DISPLAY INVISIBLE (2325 1875);
FORCEPROP 0 LAST $SEC 1
J 0
(2325 1875);
DISPLAY 0.680851 (2325 1875);
PAINT MONO (2325 1875);
DISPLAY INVISIBLE (2325 1875);
FORCEPROP 0 LAST CDS_SEC 1
J 0
(2325 1875);
DISPLAY 1.021277 (2325 1875);
DISPLAY INVISIBLE (2325 1875);
FORCEADD OFFPAGE..2
(3200 1725);
FORCEPROP 2 LAST $XR0 216 
J 0
(3389 1725);
DISPLAY 0.638298 (3389 1725);
PAINT MONO (3389 1725);
FORCEPROP 1 LAST COMMENT_BODY TRUE
J 0
(3155 1630);
DISPLAY 0.872340 (3155 1630);
PAINT GREEN (3155 1630);
DISPLAY INVISIBLE (3155 1630);
FORCEPROP 1 LAST OFFPAGE TRUE
J 0
(3525 1600);
DISPLAY 0.872340 (3525 1600);
PAINT GREEN (3525 1600);
DISPLAY INVISIBLE (3525 1600);
FORCEPROP 2 LAST CDS_LIB standard
J 0
(3200 1725);
DISPLAY INVISIBLE (3200 1725);
FORCEPROP 2 LAST PATH I36
J 0
(3400 1775);
DISPLAY 1.021277 (3400 1775);
DISPLAY INVISIBLE (3400 1775);
FORCEADD Q_RES..2
(-2025 1125);
FORCEPROP 1 LAST PART_NUMBER CS11002FB07
J 0
(-2000 950);
DISPLAY 0.510638 (-2000 950);
DISPLAY INVISIBLE (-2000 950);
FORCEPROP 1 LAST VALUE 100
J 0
(-1995 1150);
DISPLAY 0.510638 (-1995 1150);
FORCEPROP 1 LAST TOLERANCE 1%
J 0
(-1995 1100);
DISPLAY 0.510638 (-1995 1100);
FORCEPROP 1 LAST MATERIAL CHIP
J 0
(-2000 1000);
DISPLAY 0.510638 (-2000 1000);
FORCEPROP 1 LAST WATTAGE 1/16W
J 0
(-2000 1050);
DISPLAY 0.510638 (-2000 1050);
FORCEPROP 1 LAST PACK_TYPE 0402LF
J 0
(-2000 900);
DISPLAY 0.510638 (-2000 900);
FORCEPROP 1 LAST $LOCATION R4396
J 0
(-1995 1200);
DISPLAY 0.787234 (-1995 1200);
FORCEPROP 1 LASTPIN (-2025 1225) $PN 1
J 0
(-2020 1187);
DISPLAY 0.787234 (-2020 1187);
PAINT MONO (-2020 1187);
FORCEPROP 1 LASTPIN (-2025 1025) $PN 2
J 0
(-2020 1035);
DISPLAY 0.787234 (-2020 1035);
PAINT MONO (-2020 1035);
FORCEPROP 2 LAST CDS_LIB pure_quanta
J 0
(-2025 1125);
DISPLAY INVISIBLE (-2025 1125);
FORCEPROP 1 LAST PATH I4
J 0
(-1975 1300);
DISPLAY 0.978723 (-1975 1300);
PAINT WHITE (-1975 1300);
DISPLAY INVISIBLE (-1975 1300);
FORCEPROP 0 LAST CDS_LOCATION R4396
J 0
(-1975 1250);
DISPLAY 1.021277 (-1975 1250);
DISPLAY INVISIBLE (-1975 1250);
FORCEPROP 0 LAST $SEC 1
J 0
(-1975 1250);
DISPLAY 0.680851 (-1975 1250);
PAINT MONO (-1975 1250);
DISPLAY INVISIBLE (-1975 1250);
FORCEPROP 0 LAST CDS_SEC 1
J 0
(-1975 1250);
DISPLAY 1.021277 (-1975 1250);
DISPLAY INVISIBLE (-1975 1250);
FORCEADD Q_RES..1
(-725 -1475);
FORCEPROP 1 LAST PART_NUMBER CS00002JB13
J 0
(-825 -1400);
DISPLAY 0.510638 (-825 -1400);
DISPLAY INVISIBLE (-825 -1400);
FORCEPROP 1 LAST TOLERANCE 5%
J 0
(-550 -1475);
DISPLAY 0.638298 (-550 -1475);
FORCEPROP 1 LAST MATERIAL CHIP
J 0
(-825 -1350);
DISPLAY 0.510638 (-825 -1350);
FORCEPROP 1 LAST PACK_TYPE 0402LF
J 0
(-475 -1475);
DISPLAY 0.638298 (-475 -1475);
FORCEPROP 1 LAST VALUE 0
J 2
(-575 -1475);
DISPLAY 0.638298 (-575 -1475);
FORCEPROP 1 LAST WATTAGE 1/16W
J 2
(-600 -1350);
DISPLAY 0.510638 (-600 -1350);
FORCEPROP 1 LAST $LOCATION R240
J 0
(-925 -1475);
DISPLAY 0.638298 (-925 -1475);
FORCEPROP 1 LASTPIN (-825 -1475) $PN 1
J 0
(-813 -1463);
DISPLAY 0.787234 (-813 -1463);
FORCEPROP 1 LASTPIN (-625 -1475) $PN 2
J 0
(-663 -1463);
DISPLAY 0.787234 (-663 -1463);
FORCEPROP 2 LAST CDS_LIB pure_quanta
J 0
(-725 -1475);
PAINT MONO (-725 -1475);
DISPLAY INVISIBLE (-725 -1475);
FORCEPROP 1 LAST PATH I5
J 0
(-775 -1325);
DISPLAY 0.978723 (-775 -1325);
PAINT WHITE (-775 -1325);
DISPLAY INVISIBLE (-775 -1325);
FORCEPROP 2 LAST CDS_LOCATION R240
J 0
(-775 -1275);
DISPLAY 1.021277 (-775 -1275);
DISPLAY INVISIBLE (-775 -1275);
FORCEPROP 2 LAST $SEC 1
J 0
(-775 -1275);
DISPLAY 0.680851 (-775 -1275);
PAINT MONO (-775 -1275);
DISPLAY INVISIBLE (-775 -1275);
FORCEPROP 2 LAST CDS_SEC 1
J 0
(-775 -1275);
DISPLAY 1.021277 (-775 -1275);
DISPLAY INVISIBLE (-775 -1275);
FORCEADD Q_RES..1
(-1650 850);
FORCEPROP 1 LAST PART_NUMBER CS21502FB07
J 0
(-1700 950);
DISPLAY 0.787234 (-1700 950);
DISPLAY INVISIBLE (-1700 950);
FORCEPROP 1 LAST PACK_TYPE 0402LF
J 0
(-1550 750);
DISPLAY 0.638298 (-1550 750);
FORCEPROP 1 LAST VALUE 1.5K
J 2
(-1675 750);
DISPLAY 0.638298 (-1675 750);
FORCEPROP 1 LAST TOLERANCE 1%
J 0
(-1650 750);
DISPLAY 0.638298 (-1650 750);
FORCEPROP 1 LAST MATERIAL CHIP
J 0
(-1650 700);
DISPLAY 0.638298 (-1650 700);
FORCEPROP 1 LAST WATTAGE 1/16W
J 2
(-1675 700);
DISPLAY 0.638298 (-1675 700);
FORCEPROP 1 LAST LOCATION R238
J 0
(-1700 900);
DISPLAY 0.787234 (-1700 900);
FORCEPROP 1 LASTPIN (-1750 850) $PN 1
J 0
(-1738 862);
DISPLAY 0.787234 (-1738 862);
PAINT MONO (-1738 862);
FORCEPROP 1 LASTPIN (-1550 850) $PN 2
J 0
(-1588 862);
DISPLAY 0.787234 (-1588 862);
PAINT MONO (-1588 862);
FORCEPROP 2 LAST CDS_LIB pure_quanta
J 0
(-1650 850);
DISPLAY INVISIBLE (-1650 850);
FORCEPROP 1 LAST PATH I6
J 0
(-1700 1000);
DISPLAY 0.978723 (-1700 1000);
PAINT WHITE (-1700 1000);
DISPLAY INVISIBLE (-1700 1000);
FORCEPROP 0 LAST $SEC 1
J 0
(-1700 1000);
DISPLAY 0.680851 (-1700 1000);
PAINT MONO (-1700 1000);
DISPLAY INVISIBLE (-1700 1000);
FORCEPROP 0 LAST CDS_SEC 1
J 0
(-1700 1000);
DISPLAY 1.021277 (-1700 1000);
DISPLAY INVISIBLE (-1700 1000);
FORCEADD Q_RES..1
(-725 -575);
FORCEPROP 1 LAST PART_NUMBER CS00002JB13
J 0
(-825 -500);
DISPLAY 0.510638 (-825 -500);
DISPLAY INVISIBLE (-825 -500);
FORCEPROP 1 LAST MATERIAL CHIP
J 0
(-825 -450);
DISPLAY 0.510638 (-825 -450);
FORCEPROP 1 LAST WATTAGE 1/16W
J 2
(-600 -450);
DISPLAY 0.510638 (-600 -450);
FORCEPROP 1 LAST PACK_TYPE 0402LF
J 0
(-475 -575);
DISPLAY 0.638298 (-475 -575);
FORCEPROP 1 LAST TOLERANCE 5%
J 0
(-550 -575);
DISPLAY 0.638298 (-550 -575);
FORCEPROP 1 LAST VALUE 0
J 2
(-575 -575);
DISPLAY 0.638298 (-575 -575);
FORCEPROP 1 LAST $LOCATION R239
J 0
(-925 -575);
DISPLAY 0.638298 (-925 -575);
FORCEPROP 1 LASTPIN (-825 -575) $PN 1
J 0
(-813 -563);
DISPLAY 0.787234 (-813 -563);
FORCEPROP 1 LASTPIN (-625 -575) $PN 2
J 0
(-663 -563);
DISPLAY 0.787234 (-663 -563);
FORCEPROP 2 LAST CDS_LIB pure_quanta
J 0
(-725 -575);
PAINT MONO (-725 -575);
DISPLAY INVISIBLE (-725 -575);
FORCEPROP 1 LAST PATH I7
J 0
(-775 -425);
DISPLAY 0.978723 (-775 -425);
PAINT WHITE (-775 -425);
DISPLAY INVISIBLE (-775 -425);
FORCEPROP 2 LAST CDS_LOCATION R239
J 0
(-775 -375);
DISPLAY 1.021277 (-775 -375);
DISPLAY INVISIBLE (-775 -375);
FORCEPROP 2 LAST $SEC 1
J 0
(-775 -375);
DISPLAY 0.680851 (-775 -375);
PAINT MONO (-775 -375);
DISPLAY INVISIBLE (-775 -375);
FORCEPROP 2 LAST CDS_SEC 1
J 0
(-775 -375);
DISPLAY 1.021277 (-775 -375);
DISPLAY INVISIBLE (-775 -375);
FORCEADD BC847BPN..2
(-675 850);
FORCEPROP 1 LAST PART_NUMBER BA008470026
J 0
(-620 694);
DISPLAY 0.723404 (-620 694);
PAINT GREEN (-620 694);
DISPLAY INVISIBLE (-620 694);
FORCEPROP 2 LAST VALUE BC847BPN
J 0
(-600 850);
DISPLAY 1.021277 (-600 850);
FORCEPROP 1 LAST MATERIAL IC
J 0
(-620 607);
DISPLAY 0.723404 (-620 607);
PAINT GREEN (-620 607);
FORCEPROP 2 LAST PART_TYPE SMLF
J 0
(-600 900);
DISPLAY 1.021277 (-600 900);
FORCEPROP 1 LAST LOCATION Q139
J 0
(-620 801);
DISPLAY 0.723404 (-620 801);
PAINT GREEN (-620 801);
FORCEPROP 0 LASTPIN (-775 850) $PN 5
J 2
(-785 860);
DISPLAY 0.680851 (-785 860);
PAINT MONO (-785 860);
FORCEPROP 0 LASTPIN (-625 750) $PN 3
R 1
J 2
(-635 740);
DISPLAY 0.680851 (-635 740);
PAINT MONO (-635 740);
FORCEPROP 0 LASTPIN (-625 950) $PN 4
R 1
J 0
(-635 960);
DISPLAY 0.680851 (-635 960);
PAINT MONO (-635 960);
FORCEPROP 1 LAST CDS_LMAN_SYM_OUTLINE -50,50,50,-50
J 0
(-675 850);
DISPLAY 0.468085 (-675 850);
PAINT GREEN (-675 850);
DISPLAY INVISIBLE (-675 850);
FORCEPROP 1 LAST NEEDS_NO_SIZE TRUE
J 0
(-675 850);
DISPLAY 0.723404 (-675 850);
PAINT GREEN (-675 850);
DISPLAY INVISIBLE (-675 850);
FORCEPROP 2 LAST CDS_LIB pure_quanta
J 0
(-675 850);
DISPLAY INVISIBLE (-675 850);
FORCEPROP 1 LAST PATH I8
J 0
(-675 850);
DISPLAY 0.723404 (-675 850);
PAINT GREEN (-675 850);
DISPLAY INVISIBLE (-675 850);
FORCEPROP 0 LAST $SEC 2
J 0
(-600 950);
DISPLAY 0.680851 (-600 950);
PAINT MONO (-600 950);
DISPLAY INVISIBLE (-600 950);
FORCEPROP 0 LAST CDS_SEC 2
J 0
(-600 950);
DISPLAY 1.021277 (-600 950);
DISPLAY INVISIBLE (-600 950);
FORCEADD UNIVERSAL_POWER..1
(-625 1100);
FORCEPROP 3 LASTPIN (-625 1050) SIG_NAME PVNN_TERM_CPU1\g
J 0
(-615 1060);
DISPLAY 0.659574 (-615 1060);
PAINT MONO (-615 1060);
DISPLAY INVISIBLE (-615 1060);
FORCEPROP 1 LAST HDL_POWER PVNN_TERM_CPU1
J 1
(-625 1150);
DISPLAY 0.872340 (-625 1150);
PAINT GREEN (-625 1150);
FORCEPROP 2 LAST CDS_LIB logical_power
J 0
(-625 1100);
DISPLAY INVISIBLE (-625 1100);
FORCEPROP 1 LAST PATH I9
J 0
(-575 1125);
DISPLAY 0.872340 (-575 1125);
PAINT AQUA (-575 1125);
DISPLAY INVISIBLE (-575 1125);
FORCEADD QUANTA_TITLE_BLOCK_C..1
(4525 -3450);
FORCEPROP 0 LAST CDS_CON_LAST_MODIFIED Fri Aug 25 14:01:41 2023
J 0
(2640 -3435);
PAINT MONO (2640 -3435);
DISPLAY INVISIBLE (2640 -3435);
FORCEPROP 2 LAST CUSTOM_TXT_CDS <XR_PAGE_TITLE>
J 0
(-3365 1800);
DISPLAY 0.638298 (-3365 1800);
PAINT PINK (-3365 1800);
DISPLAY INVISIBLE (-3365 1800);
FORCEPROP 2 LAST CUSTOM_TXT_CDS <CON_LAST_MODIFIED>
J 0
(2640 -3435);
DISPLAY 0.978723 (2640 -3435);
FORCEPROP 2 LAST CUSTOM_TXT_CDS <CON_PAGE_NUM> OF <CON_TOTAL_PAGES>
J 0
(4079 -3432);
DISPLAY 0.978723 (4079 -3432);
FORCEPROP 2 LAST CUSTOM_TXT_CDS <Q_REV>
J 0
(4341 -3347);
DISPLAY 1.212766 (4341 -3347);
FORCEPROP 2 LAST CUSTOM_TXT_CDS <Q_PROJ>
J 0
(2143 -3348);
DISPLAY 1.212766 (2143 -3348);
FORCEPROP 2 LAST CUSTOM_TXT_CDS <Q_NUMBER>
J 0
(3122 -3347);
DISPLAY 1.212766 (3122 -3347);
FORCEPROP 2 LAST CUSTOM_TXT_CDS <NAME_1>
J 0
(1350 -3275);
FORCEPROP 2 LAST CUSTOM_TXT_CDS <NAME_2>
J 0
(1350 -3400);
FORCEPROP 1 LAST Q_TITLE SPR CPU0 & 1- PROCHOT/THERMTRIP
J 0
(-4741 -3449);
DISPLAY 2.446809 (-4741 -3449);
PAINT GREEN (-4741 -3449);
FORCEPROP 1 LAST Q_DEPT 
J 1
(762 -3401);
DISPLAY 1.957447 (762 -3401);
PAINT GREEN (762 -3401);
FORCEPROP 2 LAST CDS_LIB pure_quanta
J 0
(4525 -3450);
PAINT MONO (4525 -3450);
DISPLAY INVISIBLE (4525 -3450);
FORCEPROP 1 LAST CDS_LMAN_SYM_OUTLINE -9475,6775,100,-125
J 0
(4525 -3450);
DISPLAY 0.468085 (4525 -3450);
PAINT GREEN (4525 -3450);
DISPLAY INVISIBLE (4525 -3450);
FORCEPROP 2 LAST PAGE_BORDER TRUE
J 0
(-3365 1800);
DISPLAY 0.638298 (-3365 1800);
PAINT PINK (-3365 1800);
DISPLAY INVISIBLE (-3365 1800);
FORCEPROP 1 LAST COMMENT_BODY TRUE
J 0
(4537 -3463);
DISPLAY 0.978723 (4537 -3463);
PAINT GREEN (4537 -3463);
DISPLAY INVISIBLE (4537 -3463);
FORCEPROP 2 LAST CDS_XR_PAGE_TITLE CR-121 : @S9S_MB_2U_LIB.S9S_MB_2U(SCH_1):PAGE121
J 0
(-3365 1800);
DISPLAY 0.638298 (-3365 1800);
PAINT PINK (-3365 1800);
DISPLAY INVISIBLE (-3365 1800);
WIRE 16 -1 (-625 1050)(-625 950);
WIRE 16 -1 (-2025 1275)(-2025 1225);
WIRE 16 -1 (-2025 2625)(-2025 2575);
WIRE 16 -1 (-625 2400)(-625 2300);
WIRE 16 -1 (1450 -1025)(1450 -1125);
WIRE 16 -1 (1450 -125)(1450 -225);
WIRE 16 -1 (1725 950)(1725 850);
WIRE 16 -1 (1725 2300)(1725 2200);
WIRE 16 -1 (975 1000)(975 975);
WIRE 16 -1 (925 1000)(975 1000);
WIRE 16 -1 (975 2350)(975 2325);
WIRE 16 -1 (925 2350)(975 2350);
WIRE 16 -1 (3150 1725)(2475 1725);
FORCEPROP 2 LAST SIG_NAME H_CPU0_THERMTRIP_LVC1_N
J 0
(2515 1735);
DISPLAY 0.553191 (2515 1735);
PAINT WHITE (2515 1735);
WIRE 16 -1 (1725 2000)(1725 1725);
WIRE 16 -1 (2275 1725)(1725 1725);
WIRE 16 -1 (925 1725)(925 1850);
WIRE 16 -1 (925 1725)(1725 1725);
FORCEPROP 2 LAST SIG_NAME H_CPU0_THERMTRIP_VT_N
J 0
(1100 1735);
DISPLAY 0.553191 (1100 1735);
PAINT WHITE (1100 1735);
WIRE 16 -1 (925 2050)(925 2350);
WIRE 16 -1 (200 1950)(775 1950);
FORCEPROP 2 LAST SIG_NAME H_CPU0_THERMTRIP_R_N
J 0
(240 1960);
DISPLAY 0.510638 (240 1960);
PAINT WHITE (240 1960);
WIRE 16 -1 (3150 375)(2475 375);
FORCEPROP 2 LAST SIG_NAME H_CPU1_THERMTRIP_LVC1_N
J 0
(2515 385);
DISPLAY 0.553191 (2515 385);
PAINT WHITE (2515 385);
WIRE 16 -1 (1725 650)(1725 375);
WIRE 16 -1 (2275 375)(1725 375);
WIRE 16 -1 (925 375)(925 500);
WIRE 16 -1 (925 375)(1725 375);
FORCEPROP 2 LAST SIG_NAME H_CPU1_THERMTRIP_VT_N
J 0
(1100 385);
DISPLAY 0.553191 (1100 385);
PAINT WHITE (1100 385);
WIRE 16 -1 (925 700)(925 1000);
WIRE 16 -1 (200 600)(775 600);
FORCEPROP 2 LAST SIG_NAME H_CPU1_THERMTRIP_R_N
J 0
(240 610);
DISPLAY 0.510638 (240 610);
PAINT WHITE (240 610);
WIRE 16 -1 (1450 -425)(1450 -575);
WIRE 16 -1 (2275 -575)(1450 -575);
FORCEPROP 2 LAST SIG_NAME H_CPU0_PROCHOT_LVC1_N
J 0
(1575 -565);
DISPLAY 0.553191 (1575 -565);
PAINT WHITE (1575 -565);
WIRE 16 -1 (-625 -575)(1450 -575);
WIRE 16 -1 (1450 -1325)(1450 -1475);
WIRE 16 -1 (2275 -1475)(1450 -1475);
FORCEPROP 2 LAST SIG_NAME H_CPU1_PROCHOT_LVC1_N
J 0
(1575 -1465);
DISPLAY 0.553191 (1575 -1465);
PAINT WHITE (1575 -1465);
WIRE 16 -1 (-625 -1475)(1450 -1475);
WIRE 16 2175 (-3450 200)(4250 200);
WIRE 16 2175 (4250 2925)(4250 200);
WIRE 16 2175 (-3450 2925)(-3450 200);
WIRE 16 2175 (-3450 2925)(4250 2925);
WIRE 16 -1 (-625 2100)(-625 1950);
FORCEPROP 2 LAST SIG_NAME H_CPU0_THERMTRIP_N
J 0
(-610 1960);
DISPLAY 0.510638 (-610 1960);
PAINT WHITE (-610 1960);
WIRE 16 -1 (-625 1950)(0 1950);
WIRE 16 -1 (-1550 2200)(-775 2200);
FORCEPROP 2 LAST SIG_NAME H_CPU0_THERMTRIP_VT_R_N
J 0
(-1510 2210);
DISPLAY 0.638298 (-1510 2210);
PAINT WHITE (-1510 2210);
WIRE 16 -1 (-2025 2200)(-3050 2200);
FORCEPROP 2 LAST SIG_NAME H_CPU0_THERMTRIP_LVC1_R_N
J 0
(-2985 2210);
DISPLAY 0.553191 (-2985 2210);
PAINT WHITE (-2985 2210);
WIRE 16 -1 (-2025 2375)(-2025 2200);
WIRE 16 -1 (-1750 2200)(-2025 2200);
WIRE 16 -1 (-625 600)(0 600);
WIRE 16 -1 (-625 750)(-625 600);
FORCEPROP 2 LAST SIG_NAME H_CPU1_THERMTRIP_N
J 0
(-610 610);
DISPLAY 0.510638 (-610 610);
PAINT WHITE (-610 610);
WIRE 16 -1 (-1550 850)(-775 850);
FORCEPROP 2 LAST SIG_NAME H_CPU1_THERMTRIP_VT_R_N
J 0
(-1510 860);
DISPLAY 0.638298 (-1510 860);
PAINT WHITE (-1510 860);
WIRE 16 -1 (-825 -1475)(-2950 -1475);
FORCEPROP 2 LAST SIG_NAME H_CPU1_PROCHOT_LVC1_R_N
J 0
(-2885 -1465);
DISPLAY 0.553191 (-2885 -1465);
PAINT WHITE (-2885 -1465);
WIRE 16 -1 (-825 -575)(-2950 -575);
FORCEPROP 2 LAST SIG_NAME H_CPU0_PROCHOT_LVC1_R_N
J 0
(-2885 -565);
DISPLAY 0.553191 (-2885 -565);
PAINT WHITE (-2885 -565);
WIRE 16 -1 (-2025 850)(-3050 850);
FORCEPROP 2 LAST SIG_NAME H_CPU1_THERMTRIP_LVC1_R_N
J 0
(-2985 860);
DISPLAY 0.553191 (-2985 860);
PAINT WHITE (-2985 860);
WIRE 16 -1 (-1750 850)(-2025 850);
WIRE 16 -1 (-2025 1025)(-2025 850);
DOT 1 (-2025 850);
DOT 1 (-2025 2200);
DOT 1 (1450 -1475);
DOT 1 (1450 -575);
DOT 1 (1725 375);
DOT 1 (1725 1725);
FORCENOTE
CPLD
(-3150 -1375) 0;
DISPLAY LEFT (-3150 -1375);
DISPLAY 1.276596 (-3150 -1375);
PAINT SKYBLUE (-3150 -1375);
FORCENOTE
CPLD
(-3150 -475) 0;
DISPLAY LEFT (-3150 -475);
DISPLAY 1.276596 (-3150 -475);
PAINT SKYBLUE (-3150 -475);
FORCENOTE
CPU1
(-3250 950) 0;
DISPLAY LEFT (-3250 950);
DISPLAY 1.276596 (-3250 950);
PAINT SKYBLUE (-3250 950);
FORCENOTE
CPU0
(-3225 2250) 0;
DISPLAY LEFT (-3225 2250);
DISPLAY 1.276596 (-3225 2250);
PAINT SKYBLUE (-3225 2250);
FORCENOTE
20210907 MODIFY FOR GT
(-1750 -225) 0;
DISPLAY LEFT (-1750 -225);
DISPLAY 2.510638 (-1750 -225);
PAINT PINK (-1750 -225);
FORCENOTE
20211206 MODIFY FOR GT
(-2025 2975) 0;
DISPLAY LEFT (-2025 2975);
DISPLAY 2.510638 (-2025 2975);
PAINT PINK (-2025 2975);
FORCENOTE
20221208 CHANGE Q138,Q139 TO BA008470026
(-1000 1400) 0;
DISPLAY LEFT (-1000 1400);
DISPLAY 1.276596 (-1000 1400);
PAINT PINK (-1000 1400);
FORCENOTE
CPU1
(2300 -1600) 0;
DISPLAY LEFT (2300 -1600);
DISPLAY 1.276596 (2300 -1600);
PAINT SKYBLUE (2300 -1600);
FORCENOTE
CPU0
(2300 -700) 0;
DISPLAY LEFT (2300 -700);
DISPLAY 1.276596 (2300 -700);
PAINT SKYBLUE (2300 -700);
FORCENOTE
CPLD
(3675 350) 0;
DISPLAY LEFT (3675 350);
DISPLAY 1.276596 (3675 350);
PAINT SKYBLUE (3675 350);
FORCENOTE
CPLD
(3750 1700) 0;
DISPLAY LEFT (3750 1700);
DISPLAY 1.276596 (3750 1700);
PAINT SKYBLUE (3750 1700);
QUIT
